FILE_TYPE = CONNECTIVITY;
{Allegro Design Entry HDL 17.4-2019 S026 (4007227) 1/17/2022}
"PAGE_NUMBER" = 56;
0"NC";
1"SPI_CPU1_CLK";
2"SPI_CPU1_R_CLK";
3"PD_ESPI_CPU1_CLK2";
4"NC_CPU1_USB3_USB11_TXN";
5"NC_CPU1_USB3_USB11_TXP";
6"NC_CPU1_USB10_OC_N";
7"NC_CPU1_USB11_OC_N";
8"NC_CPU1_USB00_OC_N";
9"NC_CPU1_USB01_OC_N";
10"NC_CPU1_USB2_USB00_DN";
11"NC_CPU1_USB2_USB00_DP";
12"NC_CPU1_USB3_USB00_RXN";
13"NC_CPU1_USB3_USB00_RXP";
14"NC_CPU1_USB3_USB00_TXP";
15"NC_CPU1_USB3_USB00_TXN";
16"NC_CPU1_USB2_USB01_DN";
17"NC_CPU1_USB2_USB01_DP";
18"NC_CPU1_USB3_USB01_RXN";
19"NC_CPU1_USB3_USB01_RXP";
20"NC_CPU1_USB3_USB01_TXN";
21"NC_CPU1_USB3_USB01_TXP";
22"NC_CPU1_USB2_USB10_DN";
23"NC_CPU1_USB2_USB10_DP";
24"NC_CPU1_USB3_USB10_RXN";
25"NC_CPU1_USB3_USB10_RXP";
26"NC_CPU1_USB3_USB10_TXN";
27"NC_CPU1_USB3_USB10_TXP";
28"NC_CPU1_USB2_USB11_DN";
29"NC_CPU1_USB2_USB11_DP";
30"NC_CPU1_USB3_USB11_RXN";
31"NC_CPU1_USB3_USB11_RXP";
%"Q_RES"
"1","(-6800,5500)","0","pure_quanta","I11";
;
LOCATION"R738"
$SEC"1"
CDS_SEC"1"
VALUE"33"
PACK_TYPE"0402LF"
TOLERANCE"5%"
MATERIAL"CHIP"
WATTAGE"1/16W"
CDS_LIB"pure_quanta"
PART_NUMBER"CS03302JB10";
"B"
$PN"2"2;
"A"
$PN"1"1;
%"GENOA_SP5"
"22","(-4525,4675)","0","pure_quanta","I8";
;
LOCATION"U26"
$SEC"22"
CDS_SEC"22"
PART_TYPE"SMLF"
MATERIAL"IO"
VALUE"SOCKET6096_13568-001"
NEEDS_NO_SIZE"TRUE"
CDS_LMAN_SYM_OUTLINE"-1100,1225,1100,-1225"
CDS_LIB"pure_quanta"
PART_NUMBER"DGA^6000030";
"ESPI_RSTOUT_L||AGPIO23"
$PN"DE27"0;
"ESPI_CLK1||SPI_CLK1||AGPIO75"
$PN"DG23"0;
"ESPI_CLK2||AGPIO74"
$PN"DF27"3;
"ESPI0_ALERT_L||AGPIO108"
$PN"DJ22"0;
"AGPIO76||SPI_TPM_CS_L"
$PN"DJ25"0;
"ESPI_CLK0||SPI_CLK0||AGPIO117"
$PN"DJ27"2;
"ESPI1_ALERT_L||AGPIO110"
$PN"DF24"0;
"ESPI_RSTIN_L||KBRST_L||AGPIO129"
$PN"DJ26"0;
"USB01_OC_L||AGPIO265"
$PN"E24"9;
"SPI_CS1_L||AGPIO119"
$PN"DG26"0;
"SPI_CS2_L||AGPIO126"
$PN"DH27"0;
"ESPI0_DAT0||SPI0_DAT0||AGPIO120"
$PN"DF28"0;
"ESPI0_DAT1||SPI0_DAT1||AGPIO121"
$PN"DG22"0;
"ESPI0_DAT2||SPI0_DAT2||AGPIO122"
$PN"DJ28"0;
"ESPI0_DAT3||SPI0_DAT3||AGPIO123"
$PN"DG29"0;
"ESPI1_DAT2||SPI1_DAT2||AGPIO133"
$PN"DF25"0;
"ESPI1_DAT3||SPI1_DAT3||AGPIO134"
$PN"DG25"0;
"ESPI_CS1_L||AGPIO125"
$PN"DJ23"0;
"ESPI1_DAT0||SPI1_DAT0||AGPIO131"
$PN"DH24"0;
"ESPI1_DAT1||SPI1_DAT1||AGPIO132"
$PN"DE24"0;
"SPI_CS0_L||AGPIO118"
$PN"DF30"0;
"USB00_OC_L||AGPIO264"
$PN"E23"8;
"ESPI_CS0_L||AGPIO124"
$PN"DG28"0;
"USB11_OC_L||AGPIO17"
$PN"DH40"7;
"USB10_OC_L||AGPIO16"
$PN"DG40"6;
"USB11_TXP"
$PN"DG58"5;
"USB11_TXN"
$PN"DH58"4;
"USB11_RXP"
$PN"DJ62"31;
"USB11_RXN"
$PN"DH62"30;
"USB11_DP"
$PN"DH60"29;
"USB11_DN"
$PN"DJ60"28;
"USB10_TXP"
$PN"DH69"27;
"USB10_TXN"
$PN"DJ69"26;
"USB10_RXP"
$PN"DJ65"25;
"USB10_RXN"
$PN"DH65"24;
"USB10_DP"
$PN"DJ67"23;
"USB10_DN"
$PN"DH67"22;
"USB01_TXP"
$PN"E30"21;
"USB01_TXN"
$PN"E29"20;
"USB01_RXP"
$PN"C29"19;
"USB01_RXN"
$PN"C28"18;
"USB01_DP"
$PN"A28"17;
"USB01_DN"
$PN"A29"16;
"USB00_TXP"
$PN"C25"15;
"USB00_TXN"
$PN"C26"14;
"USB00_RXP"
$PN"E27"13;
"USB00_RXN"
$PN"E26"12;
"USB00_DP"
$PN"A26"11;
"USB00_DN"
$PN"A25"10;
END.
